# BASEBOARD_FAB2 (Tioga Pass) — schematic parts with pin connectivity, parts 4650–4650 of 4751; source: Cadence DE-HDL packaged netlist (pstxprt.dat, pstxnet.dat, pstchip.dat)

U2D1  SKX_EXT_B  IC  pkg BGA1  page 55  (pins 1015-1352 of 3647)
  BL6  VSS(597)  GROUND  = GND
  BL8  PE2_RX_DN(14)  IN  = TP_P3E_CPU1_PE2_RSR_RXN<14>
  BL10  VSS(596)  GROUND  = GND
  BL12  VSS(595)  GROUND  = GND
  BL14  CD_VCC_CORE(0)  POWER  = PVCCMCP_CPU1
  BL16  CD_VSS_VCC_CORE_SENSE  POWER  = VSENSE_PVCCMCP_CPU1_SKT_VRTN
  BL18  RSVD(138)  BI  = PVCCIOMCP_CPU1
  BL20  RSVD(137)  BI  = PVCCMCP_CPU1
  BL22  VSS(593)  GROUND  = GND
  BL24  VSS(592)  GROUND  = GND
  BL26  VCCIO(87)  POWER  = PVCCIO_CPU1
  BL60  VCCIN(154)  POWER  = PVCCIN_CPU1
  BL62  VCCIN(153)  POWER  = PVCCIN_CPU1
  BL64  VSS(591)  GROUND  = GND
  BL66  VSS(590)  GROUND  = GND
  BL68  VSS(589)  GROUND  = GND
  BL70  VSS(588)  GROUND  = GND
  BL72  VSS(587)  GROUND  = GND
  BL74  VSS(586)  GROUND  = GND
  BL76  VSS(585)  GROUND  = GND
  BL78  VSS(584)  GROUND  = GND
  BL80  VSS(583)  GROUND  = GND
  BL82  VSS(582)  GROUND  = GND
  BL84  VCCIN(152)  POWER  = PVCCIN_CPU1
  BM3  PE2_TX_DP(14)  OUT  = TP_P3E_CPU1_PE2_RSR_TXP<14>
  BM5  PE2_TX_DN(15)  OUT  = TP_P3E_CPU1_PE2_RSR_TXN<15>
  BM7  PE2_RX_DP(13)  IN  = TP_P3E_CPU1_PE2_RSR_RXP<13>
  BM9  VSS(581)  GROUND  = GND
  BM11  CD_VCCP(15)  POWER  = PVCCIOMCP_CPU1
  BM13  VSS(580)  GROUND  = GND
  BM15  VSS(579)  GROUND  = GND
  BM17  RSVD(136)  BI  = PVCCIOMCP_CPU1
  BM19  RSVD(135)  BI  = PVCCMCP_CPU1
  BM21  CD_HFI1_INT_N  IN  = TP_CD_HFI1_CPU1_INT_N
  BM23  CD_HFI1_LED_N  OUT  = TP_CD_HFI1_CPU1_LED_N
  BM25  VSS(577)  GROUND  = GND
  BM27  VCCIO(86)  POWER  = PVCCIO_CPU1
  BM61  VCCIN(151)  POWER  = PVCCIN_CPU1
  BM63  VCCIN(150)  POWER  = PVCCIN_CPU1
  BM65  VCCIN(149)  POWER  = PVCCIN_CPU1
  BM67  VCCIN(148)  POWER  = PVCCIN_CPU1
  BM69  VCCIN(147)  POWER  = PVCCIN_CPU1
  BM71  VCCIN(146)  POWER  = PVCCIN_CPU1
  BM73  VCCIN(145)  POWER  = PVCCIN_CPU1
  BM75  VCCIN(144)  POWER  = PVCCIN_CPU1
  BM77  VCCIN(143)  POWER  = PVCCIN_CPU1
  BM79  VCCIN(142)  POWER  = PVCCIN_CPU1
  BM81  VCCIN(141)  POWER  = PVCCIN_CPU1
  BM83  VCCIN(140)  POWER  = PVCCIN_CPU1
  BN4  PE2_TX_DP(13)  OUT  = TP_P3E_CPU1_PE2_RSR_TXP<13>
  BN6  VSS(576)  GROUND  = GND
  BN8  PE2_RX_DN(13)  IN  = TP_P3E_CPU1_PE2_RSR_RXN<13>
  BN10  VSS(575)  GROUND  = GND
  BN12  CD_VCCP(14)  POWER  = PVCCIOMCP_CPU1
  BN14  CD_VCCP(13)  POWER  = PVCCIOMCP_CPU1
  BN16  CD_VCC_CORE_SENSE  POWER  = VSENSE_PVCCMCP_CPU1_SKT_VSEN
  BN18  RSVD(134)  BI  = PVCCIOMCP_CPU1
  BN20  VSS(574)  GROUND  = GND
  BN22  CD_HFI0_I2CCLK  BI  = TP_SMB_CPU1_CD_HFI0_I2CCLK
  BN24  CD_HFI0_RESET_N  OUT  = TP_RST_CPU1_CD_HFI0_N
  BN26  VSS(573)  GROUND  = GND
  BN60  VCCIN(139)  POWER  = PVCCIN_CPU1
  BN62  VCCIN(138)  POWER  = PVCCIN_CPU1
  BN64  VCCIN(137)  POWER  = PVCCIN_CPU1
  BN66  VCCIN(136)  POWER  = PVCCIN_CPU1
  BN68  VCCIN(135)  POWER  = PVCCIN_CPU1
  BN70  VCCIN(134)  POWER  = PVCCIN_CPU1
  BN72  VCCIN(133)  POWER  = PVCCIN_CPU1
  BN74  VCCIN(132)  POWER  = PVCCIN_CPU1
  BN76  VCCIN(131)  POWER  = PVCCIN_CPU1
  BN78  VCCIN(130)  POWER  = PVCCIN_CPU1
  BN80  VCCIN(129)  POWER  = PVCCIN_CPU1
  BN82  VCCIN(128)  POWER  = PVCCIN_CPU1
  BN84  VCCIN(127)  POWER  = PVCCIN_CPU1
  BP3  VSS(572)  GROUND  = GND
  BP5  PE2_TX_DN(13)  OUT  = TP_P3E_CPU1_PE2_RSR_TXN<13>
  BP7  PE2_RX_DP(11)  IN  = TP_P3E_CPU1_PE2_RSR_RXP<11>
  BP9  PE2_RX_DP(12)  IN  = TP_P3E_CPU1_PE2_RSR_RXP<12>
  BP11  CD_VCCP(12)  POWER  = PVCCIOMCP_CPU1
  BP13  CD_VCCP(11)  POWER  = PVCCIOMCP_CPU1
  BP15  CD_VCCP(10)  POWER  = PVCCIOMCP_CPU1
  BP17  RSVD(133)  BI  = PVCCIOMCP_CPU1
  BP19  CD_HFI0_INT_N  IN  = TP_IRQ_CPU1_CD_HFI0_N
  BP21  RSVD(132)  BI  = PVCCMCP_CPU1
  BP23  CD_HFI0_I2CDAT  BI  = TP_SMB_CPU1_CD_HFI0_I2CDAT
  BP25  VCCIO(30)  POWER  = PVCCIO_CPU1
  BP27  VSS(571)  GROUND  = GND
  BP61  VCCIN(126)  POWER  = PVCCIN_CPU1
  BP63  VCCIN(125)  POWER  = PVCCIN_CPU1
  BP65  VCCIN(124)  POWER  = PVCCIN_CPU1
  BP67  VCCIN(123)  POWER  = PVCCIN_CPU1
  BP69  VCCIN(122)  POWER  = PVCCIN_CPU1
  BP71  VCCIN(121)  POWER  = PVCCIN_CPU1
  BP73  VCCIN(120)  POWER  = PVCCIN_CPU1
  BP75  VCCIN(119)  POWER  = PVCCIN_CPU1
  BP77  VCCIN(118)  POWER  = PVCCIN_CPU1
  BP79  VCCIN(117)  POWER  = PVCCIN_CPU1
  BP81  VCCIN(116)  POWER  = PVCCIN_CPU1
  BP83  VCCIN(115)  POWER  = PVCCIN_CPU1
  BR4  PE2_TX_DP(12)  OUT  = TP_P3E_CPU1_PE2_RSR_TXP<12>
  BR6  VSS(570)  GROUND  = GND
  BR8  PE2_RX_DN(12)  IN  = TP_P3E_CPU1_PE2_RSR_RXN<12>
  BR10  VSS(569)  GROUND  = GND
  BR12  CD_VCCP(9)  POWER  = PVCCIOMCP_CPU1
  BR14  CD_VCCP(8)  POWER  = PVCCIOMCP_CPU1
  BR16  VSS(568)  GROUND  = GND
  BR18  VSS(34)  GROUND  = GND
  BR20  CD_HFI0_MODPRST_N  IN  = TP_FM_CPU1_CD_HFI0_MODPRST_N
  BR22  RSVD(131)  BI  = PVCCMCP_CPU1
  BR24  RSVD(130)  BI  = PVCCMCP_CPU1
  BR26  VSS(127)  GROUND  = GND
  BR60  VCCIN(114)  POWER  = PVCCIN_CPU1
  BR62  VCCIN(113)  POWER  = PVCCIN_CPU1
  BR64  VSS(566)  GROUND  = GND
  BR66  VSS(565)  GROUND  = GND
  BR68  VSS(564)  GROUND  = GND
  BR70  VSS(563)  GROUND  = GND
  BR72  VSS(562)  GROUND  = GND
  BR74  VSS(561)  GROUND  = GND
  BR76  VSS(560)  GROUND  = GND
  BR78  VSS(559)  GROUND  = GND
  BR80  VSS(558)  GROUND  = GND
  BR82  VSS(557)  GROUND  = GND
  BR84  VCCIN(112)  POWER  = PVCCIN_CPU1
  BT3  VSS(556)  GROUND  = GND
  BT5  VSS(555)  GROUND  = GND
  BT7  PE2_RX_DN(11)  IN  = TP_P3E_CPU1_PE2_RSR_RXN<11>
  BT9  VSS(1064)  GROUND  = GND
  BT11  CD_VCCP(7)  POWER  = PVCCIOMCP_CPU1
  BT13  CD_VCCP(6)  POWER  = PVCCIOMCP_CPU1
  BT15  CD_VCCP(5)  POWER  = PVCCIOMCP_CPU1
  BT17  CD_VCCP_SENSE(1)  POWER  = VSENSE_PVCCIOMCP_CPU1_SKT_VSEN
  BT19  CD_HFI1_MODPRST_N  IN  = TP_CD_HFI1_CPU1_MODPRST_N
  BT21  VSS(554)  GROUND  = GND
  BT23  VSS(553)  GROUND  = GND
  BT25  VSS(552)  GROUND  = GND
  BT27  CD_VCCIN(0)  POWER  = P1V8_MCP_CPU1
  BT61  VCCIN(111)  POWER  = PVCCIN_CPU1
  BT63  VCCIN(110)  POWER  = PVCCIN_CPU1
  BT65  VCCIN(109)  POWER  = PVCCIN_CPU1
  BT67  VCCIN(108)  POWER  = PVCCIN_CPU1
  BT69  VCCIN(107)  POWER  = PVCCIN_CPU1
  BT71  VCCIN(106)  POWER  = PVCCIN_CPU1
  BT73  VCCIN(105)  POWER  = PVCCIN_CPU1
  BT75  VCCIN(104)  POWER  = PVCCIN_CPU1
  BT77  VCCIN(103)  POWER  = PVCCIN_CPU1
  BT79  VCCIN(102)  POWER  = PVCCIN_CPU1
  BT81  VCCIN(101)  POWER  = PVCCIN_CPU1
  BT83  VCCIN(100)  POWER  = PVCCIN_CPU1
  BU4  PE2_TX_DN(12)  OUT  = TP_P3E_CPU1_PE2_RSR_TXN<12>
  BU6  PE2_RX_DP(10)  IN  = TP_P3E_CPU1_PE2_RSR_RXP<10>
  BU8  VSS(551)  GROUND  = GND
  BU10  VSS(549)  GROUND  = GND
  BU12  CD_VCCP(4)  POWER  = PVCCIOMCP_CPU1
  BU14  CD_VCCP(3)  POWER  = PVCCIOMCP_CPU1
  BU16  CD_VCCP_SENSE(0)  POWER  = VSENSE_PVCCIOMCP_CPU1_SKT_VRTN
  BU18  RSVD(129)  BI  = PVCCIOMCP_CPU1
  BU20  RSVD(128)  BI  = PVCCMCP_CPU1
  BU22  RSVD(127)  BI  = PVCCMCP_CPU1
  BU24  CD_PE_REFCLK_DN  IN  = CLK_100M_CPU1_PE_REFCLK_DN
  BU26  CD_VCCIN(1)  POWER  = P1V8_MCP_CPU1
  BU60  VCCIN(99)  POWER  = PVCCIN_CPU1
  BU62  VCCIN(98)  POWER  = PVCCIN_CPU1
  BU64  VCCIN(97)  POWER  = PVCCIN_CPU1
  BU66  VCCIN(96)  POWER  = PVCCIN_CPU1
  BU68  VCCIN(95)  POWER  = PVCCIN_CPU1
  BU70  VCCIN(94)  POWER  = PVCCIN_CPU1
  BU72  VCCIN(93)  POWER  = PVCCIN_CPU1
  BU74  VCCIN(92)  POWER  = PVCCIN_CPU1
  BU76  VCCIN(91)  POWER  = PVCCIN_CPU1
  BU78  VCCIN(90)  POWER  = PVCCIN_CPU1
  BU80  VCCIN(89)  POWER  = PVCCIN_CPU1
  BU82  VCCIN(88)  POWER  = PVCCIN_CPU1
  BU84  VCCIN(87)  POWER  = PVCCIN_CPU1
  BV3  PE2_TX_DP(11)  OUT  = TP_P3E_CPU1_PE2_RSR_TXP<11>
  BV5  VSS(550)  GROUND  = GND
  BV7  PE2_RX_DN(10)  IN  = TP_P3E_CPU1_PE2_RSR_RXN<10>
  BV9  PE2_RX_DP(8)  IN  = TP_P3E_CPU1_PE2_RSR_RXP<8>
  BV11  CD_VCCP(2)  POWER  = PVCCIOMCP_CPU1
  BV13  CD_VCCP(1)  POWER  = PVCCIOMCP_CPU1
  BV15  CD_VCCP(0)  POWER  = PVCCIOMCP_CPU1
  BV17  VSS(548)  GROUND  = GND
  BV19  RSVD(126)  BI  = PVCCMCP_CPU1
  BV21  RSVD(125)  BI  = PVCCMCP_CPU1
  BV23  RSVD(124)  BI  = TP_CPU1_RSVD_124
  BV25  VSS(547)  GROUND  = GND
  BV27  CD_VCCIN(2)  POWER  = P1V8_MCP_CPU1
  BV61  VCCIN(86)  POWER  = PVCCIN_CPU1
  BV63  VCCIN(85)  POWER  = PVCCIN_CPU1
  BV65  VCCIN(84)  POWER  = PVCCIN_CPU1
  BV67  VCCIN(83)  POWER  = PVCCIN_CPU1
  BV69  VCCIN(82)  POWER  = PVCCIN_CPU1
  BV71  VCCIN(81)  POWER  = PVCCIN_CPU1
  BV73  VCCIN(80)  POWER  = PVCCIN_CPU1
  BV75  VCCIN(79)  POWER  = PVCCIN_CPU1
  BV77  VCCIN(78)  POWER  = PVCCIN_CPU1
  BV79  VCCIN(77)  POWER  = PVCCIN_CPU1
  BV81  VCCIN(76)  POWER  = PVCCIN_CPU1
  BV83  VCCIN(75)  POWER  = PVCCIN_CPU1
  BW4  PE2_TX_DN(11)  OUT  = TP_P3E_CPU1_PE2_RSR_TXN<11>
  BW6  VSS(546)  GROUND  = GND
  BW8  PE2_RX_DP(9)  IN  = TP_P3E_CPU1_PE2_RSR_RXP<9>
  BW10  RSVD(123)  BI  = TP_CPU1_RSVD_123
  BW12  VSS(544)  GROUND  = GND
  BW14  VSS(543)  GROUND  = GND
  BW16  VSS(542)  GROUND  = GND
  BW18  VSS(541)  GROUND  = GND
  BW20  RSVD(122)  BI  = PVCCMCP_CPU1
  BW22  RSVD(121)  BI  = TP_CPU1_RSVD_121
  BW24  CD_PE_REFCLK_DP  IN  = CLK_100M_CPU1_PE_REFCLK_DP
  BW26  VSS(540)  GROUND  = GND
  BW60  VCCIN(74)  POWER  = PVCCIN_CPU1
  BW62  VCCIN(73)  POWER  = PVCCIN_CPU1
  BW64  VCCIN(72)  POWER  = PVCCIN_CPU1
  BW66  VCCIN(71)  POWER  = PVCCIN_CPU1
  BW68  VCCIN(70)  POWER  = PVCCIN_CPU1
  BW70  VCCIN(69)  POWER  = PVCCIN_CPU1
  BW72  VSS(539)  GROUND  = GND
  BW74  VSS(538)  GROUND  = GND
  BW76  VSS(537)  GROUND  = GND
  BW78  VSS(536)  GROUND  = GND
  BW80  VSS(535)  GROUND  = GND
  BW82  VSS(534)  GROUND  = GND
  BW84  VCCIN(68)  POWER  = PVCCIN_CPU1
  BY3  PE2_TX_DP(9)  OUT  = TP_P3E_CPU1_PE2_RSR_TXP<9>
  BY5  PE2_TX_DP(10)  OUT  = TP_P3E_CPU1_PE2_RSR_TXP<10>
  BY7  PE2_RX_DN(9)  IN  = TP_P3E_CPU1_PE2_RSR_RXN<9>
  BY9  PE2_RX_DN(8)  IN  = TP_P3E_CPU1_PE2_RSR_RXN<8>
  BY11  VSS(533)  GROUND  = GND
  BY13  VSS(532)  GROUND  = GND
  BY15  UPI2_RX_DP(18)  IN  = GND
  BY17  UPI2_RX_DN(19)  IN  = GND
  BY19  RSVD(120)  BI  = PVCCMCP_CPU1
  BY21  CD_TDI  IN  = JTAG_MCP_CPU1_TDI
  BY23  VSS(531)  GROUND  = GND
  BY25  RSVD(119)  BI  = TP_CPU1_RSVD_119
  BY27  CD_VCCIN(3)  POWER  = P1V8_MCP_CPU1
  BY61  VCCIN(67)  POWER  = PVCCIN_CPU1
  BY63  VSS(530)  GROUND  = GND
  BY65  VSS(529)  GROUND  = GND
  BY67  VSS(528)  GROUND  = GND
  BY69  VSS(527)  GROUND  = GND
  BY71  VSS(526)  GROUND  = GND
  BY73  VCCIN(66)  POWER  = PVCCIN_CPU1
  BY75  VCCIN(65)  POWER  = PVCCIN_CPU1
  BY77  VCCIN(64)  POWER  = PVCCIN_CPU1
  BY79  VCCIN(63)  POWER  = PVCCIN_CPU1
  BY81  VCCIN(62)  POWER  = PVCCIN_CPU1
  BY83  VCCIN(61)  POWER  = PVCCIN_CPU1
  C4  VSS(1248)  GROUND  = GND
  C6  RSVD(291)  BI  = TP_CPU1_RSVD_291
  C8  VSS(1175)  GROUND  = GND
  C10  VSS(1174)  GROUND  = GND
  C12  VSS(1173)  GROUND  = GND
  C14  VSS(1172)  GROUND  = GND
  C16  VSS(1171)  GROUND  = GND
  C18  RSVD(290)  BI  = TP_CPU1_RSVD_290
  C24  RSVD(289)  BI  = TP_CPU1_RSVD_289
  C26  DDR1_DQ(50)  BI  = M_H_DQ<50>
  C28  DDR1_DQS_DP(15)  BI  = M_H_DQS_DP<15>
  C30  DDR1_DQ(48)  BI  = M_H_DQ<48>
  C32  DDR1_DQ(42)  BI  = M_H_DQ<42>
  C34  DDR1_DQS_DP(14)  BI  = M_H_DQS_DP<14>
  C36  DDR1_DQ(40)  BI  = M_H_DQ<40>
  C38  DDR0_DQ(34)  BI  = M_G_DQ<34>
  C40  DDR0_DQS_DP(13)  BI  = M_G_DQS_DP<13>
  C42  DDR0_DQ(32)  BI  = M_G_DQ<32>
  C46  VCCD012(50)  POWER  = PVDDQ_GHJ
  C48  DDR0_ODT(1)  OUT  = M_G_ODT<1>
  C50  DDR0_ODT(0)  OUT  = M_G_ODT<0>
  C52  DDR0_BA(0)  OUT  = M_G_BA<0>
  C54  DDR0_CLK_DN(1)  OUT  = M_G_CLK_DN<1>
  C56  DDR0_CLK_DN(3)  OUT  = M_G_CLK_DN<3>
  C58  DDR0_MA(3)  OUT  = M_G_MA<3>
  C60  DDR0_MA(8)  OUT  = M_G_MA<8>
  C62  DDR0_CKE(0)  OUT  = M_G_CKE<0>
  C64  DDR0_CKE(1)  OUT  = M_G_CKE<1>
  C72  DDR1_DQ(30)  BI  = M_H_DQ<30>
  C74  DDR1_DQ(25)  BI  = M_H_DQ<25>
  C76  VSS(1170)  GROUND  = GND
  C78  VSS(1169)  GROUND  = GND
  C80  VSS(1247)  GROUND  = GND
  C82  RSVD(288)  BI  = TP_CPU1_RSVD_288
  CA2  VSS(525)  GROUND  = GND
  CA4  PE2_TX_DN(10)  OUT  = TP_P3E_CPU1_PE2_RSR_TXN<10>
  CA6  VSS(524)  GROUND  = GND
  CA8  VSS(523)  GROUND  = GND
  CA10  VSS(522)  GROUND  = GND
  CA12  UPI2_TX_DP(19)  OUT  = TP_CPU1_UPI2_RSVD_DP21
  CA14  VSS(521)  GROUND  = GND
  CA16  UPI2_RX_DP(19)  IN  = GND
  CA18  VSS(520)  GROUND  = GND
  CA20  VSS(125)  GROUND  = GND
  CA22  RSVD(118)  BI  = PVCCMCP_CPU1
  CA24  RSVD(117)  BI  = TP_CPU1_RSVD_117
  CA26  VSS(519)  GROUND  = GND
  CA60  VCCIN(60)  POWER  = PVCCIN_CPU1
  CA62  VCCIN(59)  POWER  = PVCCIN_CPU1
  CA64  VSS(518)  GROUND  = GND
  CA66  VSS(517)  GROUND  = GND
  CA68  VSS(516)  GROUND  = GND
  CA70  VSS(515)  GROUND  = GND
  CA72  VCCIN(58)  POWER  = PVCCIN_CPU1
  CA74  VCCIN(57)  POWER  = PVCCIN_CPU1
  CA76  VCCIN(56)  POWER  = PVCCIN_CPU1
  CA78  VCCIN(55)  POWER  = PVCCIN_CPU1
  CA80  VCCIN(54)  POWER  = PVCCIN_CPU1
  CA82  VCCIN(53)  POWER  = PVCCIN_CPU1
  CA84  VCCIN(52)  POWER  = PVCCIN_CPU1
  CB3  PE2_TX_DN(9)  OUT  = TP_P3E_CPU1_PE2_RSR_TXN<9>
  CB5  RSVD(113)  BI  = TP_CPU1_RSVD_113
  CB7  VSS(514)  GROUND  = GND
  CB9  VSS(513)  GROUND  = GND
  CB11  UPI2_TX_DP(18)  OUT  = TP_CPU1_UPI2_RSVD_DN20
  CB13  VCCIO(29)  POWER  = PVCCIO_CPU1
  CB15  UPI2_RX_DN(18)  IN  = GND
  CB17  VCCIO(28)  POWER  = PVCCIO_CPU1
  CB19  RSVD(116)  BI  = PVCCMCP_CPU1
  CB21  RSVD(115)  BI  = PVCCMCP_CPU1
  CB23  CD_TCLK  IN  = JTAG_MCP_TCK
  CB25  RSVD(114)  BI  = TP_CPU1_RSVD_114
  CB27  VSS(512)  GROUND  = GND
  CB61  VCCIN(51)  POWER  = PVCCIN_CPU1
  CB63  VSS(511)  GROUND  = GND
  CB65  VCCSA(25)  POWER  = PVSA_CPU1
  CB67  VCCSA(24)  POWER  = PVSA_CPU1
  CB69  VCCSA(23)  POWER  = PVSA_CPU1
  CB71  VSS(510)  GROUND  = GND
  CB73  VCCIN(50)  POWER  = PVCCIN_CPU1
  CB75  VCCIN(49)  POWER  = PVCCIN_CPU1
  CB77  VCCIN(48)  POWER  = PVCCIN_CPU1
  CB79  VCCIN(47)  POWER  = PVCCIN_CPU1
  CB81  VCCIN(46)  POWER  = PVCCIN_CPU1
  CB83  VCCIN(45)  POWER  = PVCCIN_CPU1
  CC2  PE2_TX_DN(8)  OUT  = TP_P3E_CPU1_PE2_RSR_TXN<8>
  CC4  VSS(509)  GROUND  = GND
  CC6  RSVD(111)  BI  = TP_CPU1_RSVD_111
  CC8  PE2_RX_DP(7)  IN  = TP_P3E_CPU1_PE2_RSR_RXP<7>
